(kicad_pcb
	(version 20260206)
	(generator "pcbnew")
	(generator_version "10.0")
	(general
		(thickness 1.6)
		(legacy_teardrops no)
	)
	(paper "A4")
	(title_block
		(title "peb — Lightning_PEB_BRD.brd")
		(comment 1 "Lightning (Wiwynn / Facebook NVMe JBOF) / footprints 1980-1987 of 2563")
	)
	(layers
		(0 "F.Cu" signal "TOP")
		(4 "In1.Cu" signal "L2GND")
		(6 "In2.Cu" signal "L3")
		(8 "In3.Cu" signal "L4VCC")
		(10 "In4.Cu" signal "L5VCC")
		(12 "In5.Cu" signal "L6")
		(14 "In6.Cu" signal "L7GND")
		(2 "B.Cu" signal "BOTTOM")
		(9 "F.Adhes" user "F.Adhesive")
		(11 "B.Adhes" user "B.Adhesive")
		(13 "F.Paste" user "Package Geometry/Pastemask Top")
		(15 "B.Paste" user "Package Geometry/Pastemask Bottom")
		(5 "F.SilkS" user "Ref Des/Silkscreen Top")
		(7 "B.SilkS" user "Ref Des/Silkscreen Bottom")
		(1 "F.Mask" user "Board Geometry/Soldermask Top")
		(3 "B.Mask" user "Board Geometry/Soldermask Bottom")
		(17 "Dwgs.User" user "User.Drawings")
		(19 "Cmts.User" user "User.Comments")
		(21 "Eco1.User" user "User.Eco1")
		(23 "Eco2.User" user "User.Eco2")
		(25 "Edge.Cuts" user "Board Geometry/Outline")
		(27 "Margin" user)
		(31 "F.CrtYd" user "Package Geometry/Place Bound Top")
		(29 "B.CrtYd" user "Package Geometry/Place Bound Bottom")
		(35 "F.Fab" user "Ref Des/Assembly Top")
		(33 "B.Fab" user "Ref Des/Assembly Bottom")
	)
	(footprint ""
		(layer "B.Cu")
		(at 141.358874 -92.22232)
		(property "Reference" "PC86"
			(at 0 0 0)
			(layer "B.SilkS")
			(hide yes)
			(effects
				(font
					(size 1.27 1.27)
				)
				(justify mirror)
			)
		)
		(property "Value" "SCD01U25V2KX-3GP"
			(at -1.1811 -2.7051 0)
			(unlocked yes)
			(layer "B.Fab")
			(hide yes)
			(effects
				(font
					(size 1.016 1.016)
					(thickness 0.1524)
				)
				(justify mirror)
			)
		)
		(property "Device Type" "C402H22"
			(at -1.1811 -4.2291 0)
			(unlocked yes)
			(layer "B.Fab")
			(hide yes)
			(effects
				(font
					(size 1.016 1.016)
					(thickness 0.1524)
				)
				(justify mirror)
			)
		)
		(duplicate_pad_numbers_are_jumpers no)
		(fp_rect
			(start 0.4318 0.9525)
			(end -0.4318 -0.9525)
			(stroke
				(width 0)
				(type default)
			)
			(fill no)
			(layer "B.CrtYd")
		)
		(fp_rect
			(start 0.4318 0.9525)
			(end -0.4318 -0.9525)
			(stroke
				(width 0)
				(type default)
			)
			(fill no)
			(layer "B.Fab")
		)
		(pad "1" smd custom
			(at 0 -0.4445 180)
			(size 0.1524 0.1524)
			(layers "B.Cu" "B.Mask" "B.Paste")
			(net "VR_P1V8_STBY_EN_R")
			(options
				(clearance outline)
				(anchor circle)
			)
			(primitives
				(gr_poly
					(pts
						(arc
							(start 0.3048 0.2032)
							(mid 0.275042 0.275042)
							(end 0.2032 0.3048)
						)
						(arc
							(start -0.2032 0.3048)
							(mid -0.275042 0.275042)
							(end -0.3048 0.2032)
						)
						(arc
							(start -0.3048 -0.2032)
							(mid -0.275042 -0.275042)
							(end -0.2032 -0.3048)
						)
						(arc
							(start 0.2032 -0.3048)
							(mid 0.275042 -0.275042)
							(end 0.3048 -0.2032)
						)
					)
					(width 0)
					(fill yes)
				)
			)
		)
		(pad "2" smd custom
			(at 0 0.4445 180)
			(size 0.1524 0.1524)
			(layers "B.Cu" "B.Mask" "B.Paste")
			(net "GND")
			(options
				(clearance outline)
				(anchor circle)
			)
			(primitives
				(gr_poly
					(pts
						(arc
							(start 0.3048 0.2032)
							(mid 0.275042 0.275042)
							(end 0.2032 0.3048)
						)
						(arc
							(start -0.2032 0.3048)
							(mid -0.275042 0.275042)
							(end -0.3048 0.2032)
						)
						(arc
							(start -0.3048 -0.2032)
							(mid -0.275042 -0.275042)
							(end -0.2032 -0.3048)
						)
						(arc
							(start 0.2032 -0.3048)
							(mid 0.275042 -0.275042)
							(end 0.3048 -0.2032)
						)
					)
					(width 0)
					(fill yes)
				)
			)
		)
	)
	(footprint ""
		(layer "B.Cu")
		(at 142.136114 -34.44113 180)
		(property "Reference" "C223"
			(at 0 0 0)
			(layer "B.SilkS")
			(hide yes)
			(effects
				(font
					(size 1.27 1.27)
				)
				(justify mirror)
			)
		)
		(property "Value" "SCD1U10V2KX-5GP"
			(at -1.1811 -2.7051 180)
			(unlocked yes)
			(layer "B.Fab")
			(hide yes)
			(effects
				(font
					(size 1.016 1.016)
					(thickness 0.1524)
				)
				(justify mirror)
			)
		)
		(property "Device Type" "C402H22"
			(at -1.1811 -4.2291 180)
			(unlocked yes)
			(layer "B.Fab")
			(hide yes)
			(effects
				(font
					(size 1.016 1.016)
					(thickness 0.1524)
				)
				(justify mirror)
			)
		)
		(duplicate_pad_numbers_are_jumpers no)
		(fp_rect
			(start 0.4318 0.9525)
			(end -0.4318 -0.9525)
			(stroke
				(width 0)
				(type default)
			)
			(fill no)
			(layer "B.CrtYd")
		)
		(fp_rect
			(start 0.4318 0.9525)
			(end -0.4318 -0.9525)
			(stroke
				(width 0)
				(type default)
			)
			(fill no)
			(layer "B.Fab")
		)
		(pad "1" smd custom
			(at 0 -0.4445)
			(size 0.1524 0.1524)
			(layers "B.Cu" "B.Mask" "B.Paste")
			(net "GND")
			(options
				(clearance outline)
				(anchor circle)
			)
			(primitives
				(gr_poly
					(pts
						(arc
							(start 0.3048 0.2032)
							(mid 0.275042 0.275042)
							(end 0.2032 0.3048)
						)
						(arc
							(start -0.2032 0.3048)
							(mid -0.275042 0.275042)
							(end -0.3048 0.2032)
						)
						(arc
							(start -0.3048 -0.2032)
							(mid -0.275042 -0.275042)
							(end -0.2032 -0.3048)
						)
						(arc
							(start 0.2032 -0.3048)
							(mid 0.275042 -0.275042)
							(end 0.3048 -0.2032)
						)
					)
					(width 0)
					(fill yes)
				)
			)
		)
		(pad "2" smd custom
			(at 0 0.4445)
			(size 0.1524 0.1524)
			(layers "B.Cu" "B.Mask" "B.Paste")
			(net "P3V3_STBY")
			(options
				(clearance outline)
				(anchor circle)
			)
			(primitives
				(gr_poly
					(pts
						(arc
							(start 0.3048 0.2032)
							(mid 0.275042 0.275042)
							(end 0.2032 0.3048)
						)
						(arc
							(start -0.2032 0.3048)
							(mid -0.275042 0.275042)
							(end -0.3048 0.2032)
						)
						(arc
							(start -0.3048 -0.2032)
							(mid -0.275042 -0.275042)
							(end -0.2032 -0.3048)
						)
						(arc
							(start 0.2032 -0.3048)
							(mid 0.275042 -0.275042)
							(end 0.3048 -0.2032)
						)
					)
					(width 0)
					(fill yes)
				)
			)
		)
	)
	(footprint ""
		(layer "B.Cu")
		(at 54.4322 -115.7732)
		(property "Reference" "R490"
			(at 0 0 0)
			(layer "B.SilkS")
			(hide yes)
			(effects
				(font
					(size 1.27 1.27)
				)
				(justify mirror)
			)
		)
		(property "Value" "0R2J-2-GP"
			(at -0.064008 -3.993896 0)
			(unlocked yes)
			(layer "B.Fab")
			(hide yes)
			(effects
				(font
					(size 1.016 1.016)
					(thickness 0.1524)
				)
				(justify mirror)
			)
		)
		(property "Device Type" "R402H16"
			(at -0.064008 -5.517896 0)
			(unlocked yes)
			(layer "B.Fab")
			(hide yes)
			(effects
				(font
					(size 1.016 1.016)
					(thickness 0.1524)
				)
				(justify mirror)
			)
		)
		(duplicate_pad_numbers_are_jumpers no)
		(fp_line
			(start -0.508 -0.9398)
			(end 0.508 -0.9398)
			(stroke
				(width 0.1524)
				(type default)
			)
			(layer "B.SilkS")
		)
		(fp_line
			(start 0.508 -0.9398)
			(end 0.508 0.9398)
			(stroke
				(width 0.1524)
				(type default)
			)
			(layer "B.SilkS")
		)
		(fp_rect
			(start 0.508 0.9398)
			(end -0.508 -0.9398)
			(stroke
				(width 0)
				(type default)
			)
			(fill no)
			(layer "B.CrtYd")
		)
		(fp_rect
			(start 0.508 0.9398)
			(end -0.508 -0.9398)
			(stroke
				(width 0)
				(type default)
			)
			(fill no)
			(layer "B.Fab")
		)
		(pad "1" smd custom
			(at 0 -0.4445 180)
			(size 0.1397 0.1397)
			(layers "B.Cu" "B.Mask" "B.Paste")
			(net "BMC0_SDA12_R")
			(options
				(clearance outline)
				(anchor circle)
			)
			(primitives
				(gr_poly
					(pts
						(arc
							(start -0.1778 0.2794)
							(mid -0.249642 0.249642)
							(end -0.2794 0.1778)
						)
						(arc
							(start -0.2794 -0.1778)
							(mid -0.249642 -0.249642)
							(end -0.1778 -0.2794)
						)
						(arc
							(start 0.1778 -0.2794)
							(mid 0.249642 -0.249642)
							(end 0.2794 -0.1778)
						)
						(arc
							(start 0.2794 0.1778)
							(mid 0.249642 0.249642)
							(end 0.1778 0.2794)
						)
					)
					(width 0)
					(fill yes)
				)
			)
		)
		(pad "2" smd custom
			(at 0 0.4445 180)
			(size 0.1397 0.1397)
			(layers "B.Cu" "B.Mask" "B.Paste")
			(net "BMC_I2C12_MINI6_SDA_S")
			(options
				(clearance outline)
				(anchor circle)
			)
			(primitives
				(gr_poly
					(pts
						(arc
							(start -0.1778 0.2794)
							(mid -0.249642 0.249642)
							(end -0.2794 0.1778)
						)
						(arc
							(start -0.2794 -0.1778)
							(mid -0.249642 -0.249642)
							(end -0.1778 -0.2794)
						)
						(arc
							(start 0.1778 -0.2794)
							(mid 0.249642 -0.249642)
							(end 0.2794 -0.1778)
						)
						(arc
							(start 0.2794 0.1778)
							(mid 0.249642 0.249642)
							(end 0.1778 0.2794)
						)
					)
					(width 0)
					(fill yes)
				)
			)
		)
	)
	(footprint ""
		(layer "B.Cu")
		(at 235.585 -56.9976 90)
		(property "Reference" "C519"
			(at 0 0 90)
			(layer "B.SilkS")
			(hide yes)
			(effects
				(font
					(size 1.27 1.27)
				)
				(justify mirror)
			)
		)
		(property "Value" "SCD1U16V1KX-1-GP"
			(at 2.8321 -1.7399 90)
			(unlocked yes)
			(layer "B.Fab")
			(hide yes)
			(effects
				(font
					(size 1.016 1.016)
					(thickness 0.1524)
				)
				(justify mirror)
			)
		)
		(property "Device Type" "C0201H13"
			(at 2.8321 -3.2639 90)
			(unlocked yes)
			(layer "B.Fab")
			(hide yes)
			(effects
				(font
					(size 1.016 1.016)
					(thickness 0.1524)
				)
				(justify mirror)
			)
		)
		(duplicate_pad_numbers_are_jumpers no)
		(fp_rect
			(start 0.2794 0.6477)
			(end -0.2794 -0.6477)
			(stroke
				(width 0)
				(type default)
			)
			(fill no)
			(layer "B.CrtYd")
		)
		(fp_rect
			(start 0.2794 0.6477)
			(end -0.2794 -0.6477)
			(stroke
				(width 0)
				(type default)
			)
			(fill no)
			(layer "B.Fab")
		)
		(pad "1" smd custom
			(at 0 -0.2794 270)
			(size 0.0762 0.0762)
			(layers "B.Cu" "B.Mask" "B.Paste")
			(net "DUT_AVD_TX")
			(options
				(clearance outline)
				(anchor circle)
			)
			(primitives
				(gr_poly
					(pts
						(arc
							(start 0.1524 0.127)
							(mid 0.137521 0.162921)
							(end 0.1016 0.1778)
						)
						(arc
							(start -0.1016 0.1778)
							(mid -0.137521 0.162921)
							(end -0.1524 0.127)
						)
						(arc
							(start -0.1524 -0.127)
							(mid -0.137521 -0.162921)
							(end -0.1016 -0.1778)
						)
						(arc
							(start 0.1016 -0.1778)
							(mid 0.137521 -0.162921)
							(end 0.1524 -0.127)
						)
					)
					(width 0)
					(fill yes)
				)
			)
		)
		(pad "2" smd custom
			(at 0 0.2794 270)
			(size 0.0762 0.0762)
			(layers "B.Cu" "B.Mask" "B.Paste")
			(net "GND")
			(options
				(clearance outline)
				(anchor circle)
			)
			(primitives
				(gr_poly
					(pts
						(arc
							(start 0.1524 0.127)
							(mid 0.137521 0.162921)
							(end 0.1016 0.1778)
						)
						(arc
							(start -0.1016 0.1778)
							(mid -0.137521 0.162921)
							(end -0.1524 0.127)
						)
						(arc
							(start -0.1524 -0.127)
							(mid -0.137521 -0.162921)
							(end -0.1016 -0.1778)
						)
						(arc
							(start 0.1016 -0.1778)
							(mid 0.137521 -0.162921)
							(end 0.1524 -0.127)
						)
					)
					(width 0)
					(fill yes)
				)
			)
		)
	)
	(footprint ""
		(layer "B.Cu")
		(at 243.586 -59.99734 90)
		(property "Reference" "C505"
			(at 0 0 90)
			(layer "B.SilkS")
			(hide yes)
			(effects
				(font
					(size 1.27 1.27)
				)
				(justify mirror)
			)
		)
		(property "Value" "SCD1U16V1KX-1-GP"
			(at 2.8321 -1.7399 90)
			(unlocked yes)
			(layer "B.Fab")
			(hide yes)
			(effects
				(font
					(size 1.016 1.016)
					(thickness 0.1524)
				)
				(justify mirror)
			)
		)
		(property "Device Type" "C0201H13"
			(at 2.8321 -3.2639 90)
			(unlocked yes)
			(layer "B.Fab")
			(hide yes)
			(effects
				(font
					(size 1.016 1.016)
					(thickness 0.1524)
				)
				(justify mirror)
			)
		)
		(duplicate_pad_numbers_are_jumpers no)
		(fp_rect
			(start 0.2794 0.6477)
			(end -0.2794 -0.6477)
			(stroke
				(width 0)
				(type default)
			)
			(fill no)
			(layer "B.CrtYd")
		)
		(fp_rect
			(start 0.2794 0.6477)
			(end -0.2794 -0.6477)
			(stroke
				(width 0)
				(type default)
			)
			(fill no)
			(layer "B.Fab")
		)
		(pad "1" smd custom
			(at 0 -0.2794 270)
			(size 0.0762 0.0762)
			(layers "B.Cu" "B.Mask" "B.Paste")
			(net "DUT_AVD_TX")
			(options
				(clearance outline)
				(anchor circle)
			)
			(primitives
				(gr_poly
					(pts
						(arc
							(start 0.1524 0.127)
							(mid 0.137521 0.162921)
							(end 0.1016 0.1778)
						)
						(arc
							(start -0.1016 0.1778)
							(mid -0.137521 0.162921)
							(end -0.1524 0.127)
						)
						(arc
							(start -0.1524 -0.127)
							(mid -0.137521 -0.162921)
							(end -0.1016 -0.1778)
						)
						(arc
							(start 0.1016 -0.1778)
							(mid 0.137521 -0.162921)
							(end 0.1524 -0.127)
						)
					)
					(width 0)
					(fill yes)
				)
			)
		)
		(pad "2" smd custom
			(at 0 0.2794 270)
			(size 0.0762 0.0762)
			(layers "B.Cu" "B.Mask" "B.Paste")
			(net "GND")
			(options
				(clearance outline)
				(anchor circle)
			)
			(primitives
				(gr_poly
					(pts
						(arc
							(start 0.1524 0.127)
							(mid 0.137521 0.162921)
							(end 0.1016 0.1778)
						)
						(arc
							(start -0.1016 0.1778)
							(mid -0.137521 0.162921)
							(end -0.1524 0.127)
						)
						(arc
							(start -0.1524 -0.127)
							(mid -0.137521 -0.162921)
							(end -0.1016 -0.1778)
						)
						(arc
							(start 0.1016 -0.1778)
							(mid 0.137521 -0.162921)
							(end 0.1524 -0.127)
						)
					)
					(width 0)
					(fill yes)
				)
			)
		)
	)
	(footprint ""
		(layer "B.Cu")
		(at 310.007 -64.643 180)
		(property "Reference" "PG36"
			(at 0 0 0)
			(layer "B.SilkS")
			(hide yes)
			(effects
				(font
					(size 1.27 1.27)
				)
				(justify mirror)
			)
		)
		(property "Value" "GAP-CLOSE-PWR-3-GP"
			(at -0.0254 -6.5786 180)
			(unlocked yes)
			(layer "B.Fab")
			(hide yes)
			(effects
				(font
					(size 1.016 1.016)
					(thickness 0.1524)
				)
				(justify mirror)
			)
		)
		(property "Device Type" "GAP-CLOSE-PWR-3"
			(at -0.0254 -8.255 180)
			(unlocked yes)
			(layer "B.Fab")
			(hide yes)
			(effects
				(font
					(size 1.016 1.016)
					(thickness 0.1524)
				)
				(justify mirror)
			)
		)
		(duplicate_pad_numbers_are_jumpers no)
		(fp_rect
			(start 0.7112 0.4572)
			(end -0.7112 -0.4572)
			(stroke
				(width 0)
				(type default)
			)
			(fill no)
			(layer "B.CrtYd")
		)
		(fp_poly
			(pts
				(xy 0.7112 -0.4572) (xy -0.7112 -0.4572) (xy -0.7112 0.4572) (xy 0.7112 0.4572)
			)
			(stroke
				(width 0)
				(type default)
			)
			(fill no)
			(layer "B.Fab")
		)
		(pad "1" smd rect
			(at 0.3048 0)
			(size 0.6604 0.762)
			(layers "B.Cu" "B.Mask" "B.Paste")
			(net "DUT_VDD")
		)
		(pad "2" smd rect
			(at -0.3048 0)
			(size 0.6604 0.762)
			(layers "B.Cu" "B.Mask" "B.Paste")
			(net "P0V9_E")
		)
	)
	(footprint ""
		(layer "B.Cu")
		(at 243.1288 -43.997372 -90)
		(property "Reference" "C451"
			(at 0 0 90)
			(layer "B.SilkS")
			(hide yes)
			(effects
				(font
					(size 1.27 1.27)
				)
				(justify mirror)
			)
		)
		(property "Value" "SCD1U16V1KX-1-GP"
			(at 2.8321 -1.7399 270)
			(unlocked yes)
			(layer "B.Fab")
			(hide yes)
			(effects
				(font
					(size 1.016 1.016)
					(thickness 0.1524)
				)
				(justify mirror)
			)
		)
		(property "Device Type" "C0201H13"
			(at 2.8321 -3.2639 270)
			(unlocked yes)
			(layer "B.Fab")
			(hide yes)
			(effects
				(font
					(size 1.016 1.016)
					(thickness 0.1524)
				)
				(justify mirror)
			)
		)
		(duplicate_pad_numbers_are_jumpers no)
		(fp_rect
			(start 0.2794 0.6477)
			(end -0.2794 -0.6477)
			(stroke
				(width 0)
				(type default)
			)
			(fill no)
			(layer "B.CrtYd")
		)
		(fp_rect
			(start 0.2794 0.6477)
			(end -0.2794 -0.6477)
			(stroke
				(width 0)
				(type default)
			)
			(fill no)
			(layer "B.Fab")
		)
		(pad "1" smd custom
			(at 0 -0.2794 90)
			(size 0.0762 0.0762)
			(layers "B.Cu" "B.Mask" "B.Paste")
			(net "DUT_VDD")
			(options
				(clearance outline)
				(anchor circle)
			)
			(primitives
				(gr_poly
					(pts
						(arc
							(start 0.1524 0.127)
							(mid 0.137521 0.162921)
							(end 0.1016 0.1778)
						)
						(arc
							(start -0.1016 0.1778)
							(mid -0.137521 0.162921)
							(end -0.1524 0.127)
						)
						(arc
							(start -0.1524 -0.127)
							(mid -0.137521 -0.162921)
							(end -0.1016 -0.1778)
						)
						(arc
							(start 0.1016 -0.1778)
							(mid 0.137521 -0.162921)
							(end 0.1524 -0.127)
						)
					)
					(width 0)
					(fill yes)
				)
			)
		)
		(pad "2" smd custom
			(at 0 0.2794 90)
			(size 0.0762 0.0762)
			(layers "B.Cu" "B.Mask" "B.Paste")
			(net "GND")
			(options
				(clearance outline)
				(anchor circle)
			)
			(primitives
				(gr_poly
					(pts
						(arc
							(start 0.1524 0.127)
							(mid 0.137521 0.162921)
							(end 0.1016 0.1778)
						)
						(arc
							(start -0.1016 0.1778)
							(mid -0.137521 0.162921)
							(end -0.1524 0.127)
						)
						(arc
							(start -0.1524 -0.127)
							(mid -0.137521 -0.162921)
							(end -0.1016 -0.1778)
						)
						(arc
							(start 0.1016 -0.1778)
							(mid 0.137521 -0.162921)
							(end 0.1524 -0.127)
						)
					)
					(width 0)
					(fill yes)
				)
			)
		)
	)
	(footprint ""
		(layer "B.Cu")
		(at 245.1354 -43.997372 -90)
		(property "Reference" "C450"
			(at 0 0 90)
			(layer "B.SilkS")
			(hide yes)
			(effects
				(font
					(size 1.27 1.27)
				)
				(justify mirror)
			)
		)
		(property "Value" "SCD1U16V1KX-1-GP"
			(at 2.8321 -1.7399 270)
			(unlocked yes)
			(layer "B.Fab")
			(hide yes)
			(effects
				(font
					(size 1.016 1.016)
					(thickness 0.1524)
				)
				(justify mirror)
			)
		)
		(property "Device Type" "C0201H13"
			(at 2.8321 -3.2639 270)
			(unlocked yes)
			(layer "B.Fab")
			(hide yes)
			(effects
				(font
					(size 1.016 1.016)
					(thickness 0.1524)
				)
				(justify mirror)
			)
		)
		(duplicate_pad_numbers_are_jumpers no)
		(fp_rect
			(start 0.2794 0.6477)
			(end -0.2794 -0.6477)
			(stroke
				(width 0)
				(type default)
			)
			(fill no)
			(layer "B.CrtYd")
		)
		(fp_rect
			(start 0.2794 0.6477)
			(end -0.2794 -0.6477)
			(stroke
				(width 0)
				(type default)
			)
			(fill no)
			(layer "B.Fab")
		)
		(pad "1" smd custom
			(at 0 -0.2794 90)
			(size 0.0762 0.0762)
			(layers "B.Cu" "B.Mask" "B.Paste")
			(net "DUT_VDD")
			(options
				(clearance outline)
				(anchor circle)
			)
			(primitives
				(gr_poly
					(pts
						(arc
							(start 0.1524 0.127)
							(mid 0.137521 0.162921)
							(end 0.1016 0.1778)
						)
						(arc
							(start -0.1016 0.1778)
							(mid -0.137521 0.162921)
							(end -0.1524 0.127)
						)
						(arc
							(start -0.1524 -0.127)
							(mid -0.137521 -0.162921)
							(end -0.1016 -0.1778)
						)
						(arc
							(start 0.1016 -0.1778)
							(mid 0.137521 -0.162921)
							(end 0.1524 -0.127)
						)
					)
					(width 0)
					(fill yes)
				)
			)
		)
		(pad "2" smd custom
			(at 0 0.2794 90)
			(size 0.0762 0.0762)
			(layers "B.Cu" "B.Mask" "B.Paste")
			(net "GND")
			(options
				(clearance outline)
				(anchor circle)
			)
			(primitives
				(gr_poly
					(pts
						(arc
							(start 0.1524 0.127)
							(mid 0.137521 0.162921)
							(end 0.1016 0.1778)
						)
						(arc
							(start -0.1016 0.1778)
							(mid -0.137521 0.162921)
							(end -0.1524 0.127)
						)
						(arc
							(start -0.1524 -0.127)
							(mid -0.137521 -0.162921)
							(end -0.1016 -0.1778)
						)
						(arc
							(start 0.1016 -0.1778)
							(mid 0.137521 -0.162921)
							(end 0.1524 -0.127)
						)
					)
					(width 0)
					(fill yes)
				)
			)
		)
	)
)
